# SCM (Grand Teton) — schematic netlist excerpt (pin names and nets, part order shuffled) for the footprints in the layout excerpt that follows; sources: Cadence DE-HDL packaged netlist, KiCad conversion of 12092022_DA0F0TMDCD0_F0T_Management_Board_D_brd_V3_OCP.brd

C256  Q_CAP  1UF 25V 10% X6S  pkg C0402  page 34 : A = PVCCIO_AUX_PLD ; B = GND
R304  Q_RES  0 5% CHIP  pkg 0402LF  page 41 : A = P3V3_AUX ; B = VCCIO2

(kicad_pcb
	(version 20260206)
	(generator "pcbnew")
	(generator_version "10.0")
	(general
		(thickness 1.6)
		(legacy_teardrops no)
	)
	(paper "A4")
	(title_block
		(title "12092022_DA0F0TMDCD0_F0T_Management_Board_D_brd_V3_OCP.brd")
		(comment 1 "Grand Teton / footprints 1396-1397 of 1440")
	)
	(layers
		(0 "F.Cu" signal "TOP")
		(4 "In1.Cu" signal "GND")
		(6 "In2.Cu" signal "IN1")
		(8 "In3.Cu" signal "GND1")
		(10 "In4.Cu" signal "IN2")
		(12 "In5.Cu" signal "VCC")
		(14 "In6.Cu" signal "VCC1")
		(16 "In7.Cu" signal "IN3")
		(18 "In8.Cu" signal "GND2")
		(20 "In9.Cu" signal "IN4")
		(22 "In10.Cu" signal "GND3")
		(2 "B.Cu" signal "BOTTOM")
		(9 "F.Adhes" user "F.Adhesive")
		(11 "B.Adhes" user "B.Adhesive")
		(13 "F.Paste" user "Package Geometry/Pastemask Top")
		(15 "B.Paste" user "Package Geometry/Pastemask Bottom")
		(5 "F.SilkS" user "Ref Des/Silkscreen Top")
		(7 "B.SilkS" user "Ref Des/Silkscreen Bottom")
		(1 "F.Mask" user "Board Geometry/Soldermask Top")
		(3 "B.Mask" user "Board Geometry/Soldermask Bottom")
		(17 "Dwgs.User" user "User.Drawings")
		(19 "Cmts.User" user "User.Comments")
		(21 "Eco1.User" user "User.Eco1")
		(23 "Eco2.User" user "User.Eco2")
		(25 "Edge.Cuts" user "Board Geometry/Outline")
		(27 "Margin" user)
		(31 "F.CrtYd" user "Package Geometry/Place Bound Top")
		(29 "B.CrtYd" user "Package Geometry/Place Bound Bottom")
		(35 "F.Fab" user "Ref Des/Assembly Top")
		(33 "B.Fab" user "Ref Des/Assembly Bottom")
	)
	(footprint ""
		(layer "B.Cu")
		(at 32.766 -90.805 180)
		(property "Reference" "C256"
			(at 0 0 0)
			(layer "B.SilkS")
			(hide yes)
			(effects
				(font
					(size 1.27 1.27)
				)
				(justify mirror)
			)
		)
		(property "Value" ""
			(at 0 0 0)
			(layer "B.Fab")
			(effects
				(font
					(size 1.27 1.27)
				)
				(justify mirror)
			)
		)
		(duplicate_pad_numbers_are_jumpers no)
		(fp_line
			(start 0.7874 0.4064)
			(end 0.7874 -0.4064)
			(stroke
				(width 0.1524)
				(type default)
			)
			(layer "B.SilkS")
		)
		(fp_line
			(start 0.7874 -0.4064)
			(end -0.7874 -0.4064)
			(stroke
				(width 0.1524)
				(type default)
			)
			(layer "B.SilkS")
		)
		(fp_line
			(start -0.7874 0.4064)
			(end 0.7874 0.4064)
			(stroke
				(width 0.1524)
				(type default)
			)
			(layer "B.SilkS")
		)
		(fp_line
			(start -0.7874 -0.4064)
			(end -0.7874 0.4064)
			(stroke
				(width 0.1524)
				(type default)
			)
			(layer "B.SilkS")
		)
		(fp_line
			(start 0.67945 0.3048)
			(end 0.67945 -0.305054)
			(stroke
				(width 0.1)
				(type default)
			)
			(layer "B.Fab")
		)
		(fp_line
			(start 0.67945 -0.305054)
			(end 0.12065 -0.305054)
			(stroke
				(width 0.1)
				(type default)
			)
			(layer "B.Fab")
		)
		(fp_line
			(start 0.12065 0.3048)
			(end 0.67945 0.3048)
			(stroke
				(width 0.1)
				(type default)
			)
			(layer "B.Fab")
		)
		(fp_line
			(start 0.12065 0.2794)
			(end 0.12065 0.3048)
			(stroke
				(width 0.1)
				(type default)
			)
			(layer "B.Fab")
		)
		(fp_line
			(start 0.12065 -0.2794)
			(end -0.12065 -0.2794)
			(stroke
				(width 0.1)
				(type default)
			)
			(layer "B.Fab")
		)
		(fp_line
			(start 0.12065 -0.305054)
			(end 0.12065 -0.2794)
			(stroke
				(width 0.1)
				(type default)
			)
			(layer "B.Fab")
		)
		(fp_line
			(start -0.120396 0.3048)
			(end -0.120396 0.2794)
			(stroke
				(width 0.1)
				(type default)
			)
			(layer "B.Fab")
		)
		(fp_line
			(start -0.120396 0.2794)
			(end 0.12065 0.2794)
			(stroke
				(width 0.1)
				(type default)
			)
			(layer "B.Fab")
		)
		(fp_line
			(start -0.12065 -0.2794)
			(end -0.12065 -0.3048)
			(stroke
				(width 0.1)
				(type default)
			)
			(layer "B.Fab")
		)
		(fp_line
			(start -0.12065 -0.3048)
			(end -0.67945 -0.3048)
			(stroke
				(width 0.1)
				(type default)
			)
			(layer "B.Fab")
		)
		(fp_line
			(start -0.67945 0.3048)
			(end -0.120396 0.3048)
			(stroke
				(width 0.1)
				(type default)
			)
			(layer "B.Fab")
		)
		(fp_line
			(start -0.67945 -0.3048)
			(end -0.67945 0.3048)
			(stroke
				(width 0.1)
				(type default)
			)
			(layer "B.Fab")
		)
		(pad "1" smd circle
			(at 0.40005 0)
			(size 0 0)
			(layers "B.Cu" "B.Mask" "B.Paste")
			(net "PVCCIO_AUX_PLD")
		)
		(pad "2" smd circle
			(at -0.40005 0)
			(size 0 0)
			(layers "B.Cu" "B.Mask" "B.Paste")
			(net "GND")
		)
	)
	(footprint ""
		(layer "B.Cu")
		(at 19.05 -98.679 90)
		(property "Reference" "R304"
			(at 0 0 90)
			(layer "B.SilkS")
			(hide yes)
			(effects
				(font
					(size 1.27 1.27)
				)
				(justify mirror)
			)
		)
		(property "Value" ""
			(at 0 0 90)
			(layer "B.Fab")
			(effects
				(font
					(size 1.27 1.27)
				)
				(justify mirror)
			)
		)
		(duplicate_pad_numbers_are_jumpers no)
		(fp_line
			(start 0.7874 -0.4064)
			(end -0.7874 -0.4064)
			(stroke
				(width 0.1524)
				(type default)
			)
			(layer "B.SilkS")
		)
		(fp_line
			(start -0.7874 -0.4064)
			(end -0.7874 0.4064)
			(stroke
				(width 0.1524)
				(type default)
			)
			(layer "B.SilkS")
		)
		(fp_line
			(start 0.7874 0.4064)
			(end 0.7874 -0.4064)
			(stroke
				(width 0.1524)
				(type default)
			)
			(layer "B.SilkS")
		)
		(fp_line
			(start -0.7874 0.4064)
			(end 0.7874 0.4064)
			(stroke
				(width 0.1524)
				(type default)
			)
			(layer "B.SilkS")
		)
		(fp_line
			(start 0.67945 -0.305054)
			(end 0.12065 -0.305054)
			(stroke
				(width 0.1)
				(type default)
			)
			(layer "B.Fab")
		)
		(fp_line
			(start 0.12065 -0.305054)
			(end 0.12065 -0.2794)
			(stroke
				(width 0.1)
				(type default)
			)
			(layer "B.Fab")
		)
		(fp_line
			(start -0.12065 -0.3048)
			(end -0.67945 -0.3048)
			(stroke
				(width 0.1)
				(type default)
			)
			(layer "B.Fab")
		)
		(fp_line
			(start -0.67945 -0.3048)
			(end -0.67945 0.3048)
			(stroke
				(width 0.1)
				(type default)
			)
			(layer "B.Fab")
		)
		(fp_line
			(start 0.12065 -0.2794)
			(end -0.12065 -0.2794)
			(stroke
				(width 0.1)
				(type default)
			)
			(layer "B.Fab")
		)
		(fp_line
			(start -0.12065 -0.2794)
			(end -0.12065 -0.3048)
			(stroke
				(width 0.1)
				(type default)
			)
			(layer "B.Fab")
		)
		(fp_line
			(start 0.12065 0.2794)
			(end 0.12065 0.3048)
			(stroke
				(width 0.1)
				(type default)
			)
			(layer "B.Fab")
		)
		(fp_line
			(start -0.120396 0.2794)
			(end 0.12065 0.2794)
			(stroke
				(width 0.1)
				(type default)
			)
			(layer "B.Fab")
		)
		(fp_line
			(start 0.67945 0.3048)
			(end 0.67945 -0.305054)
			(stroke
				(width 0.1)
				(type default)
			)
			(layer "B.Fab")
		)
		(fp_line
			(start 0.12065 0.3048)
			(end 0.67945 0.3048)
			(stroke
				(width 0.1)
				(type default)
			)
			(layer "B.Fab")
		)
		(fp_line
			(start -0.120396 0.3048)
			(end -0.120396 0.2794)
			(stroke
				(width 0.1)
				(type default)
			)
			(layer "B.Fab")
		)
		(fp_line
			(start -0.67945 0.3048)
			(end -0.120396 0.3048)
			(stroke
				(width 0.1)
				(type default)
			)
			(layer "B.Fab")
		)
		(pad "1" smd circle
			(at 0.40005 0 270)
			(size 0 0)
			(layers "B.Cu" "B.Mask" "B.Paste")
			(net "P3V3_AUX")
		)
		(pad "2" smd circle
			(at -0.40005 0 270)
			(size 0 0)
			(layers "B.Cu" "B.Mask" "B.Paste")
			(net "VCCIO2")
		)
	)
)
